(kicad_pcb
	(version 20241229)
	(generator "pcbnew")
	(generator_version "9.0")
	(general
		(thickness 1.6642)
		(legacy_teardrops no)
	)
	(paper "A3")
	(title_block
		(title "PolarFire SoM")
		(date "2025-07-22")
		(rev "1.1.4")
		(company "Antmicro Ltd")
		(comment 1 "www.antmicro.com")
		(comment 9 "footprints 393-397 of 470")
	)
	(layers
		(0 "F.Cu" mixed)
		(4 "In1.Cu" power)
		(6 "In2.Cu" signal)
		(8 "In3.Cu" power)
		(10 "In4.Cu" signal)
		(12 "In5.Cu" power)
		(14 "In6.Cu" power)
		(16 "In7.Cu" signal)
		(18 "In8.Cu" power)
		(20 "In9.Cu" signal)
		(22 "In10.Cu" power)
		(24 "In11.Cu" signal)
		(26 "In12.Cu" signal)
		(2 "B.Cu" mixed)
		(9 "F.Adhes" user "F.Adhesive")
		(11 "B.Adhes" user "B.Adhesive")
		(13 "F.Paste" user)
		(15 "B.Paste" user)
		(5 "F.SilkS" user "F.Silkscreen")
		(7 "B.SilkS" user "B.Silkscreen")
		(1 "F.Mask" user)
		(3 "B.Mask" user)
		(17 "Dwgs.User" user "User.Drawings")
		(19 "Cmts.User" user "User.Comments")
		(21 "Eco1.User" user "User.Eco1")
		(23 "Eco2.User" user "User.Eco2")
		(25 "Edge.Cuts" user)
		(27 "Margin" user)
		(31 "F.CrtYd" user "F.Courtyard")
		(29 "B.CrtYd" user "B.Courtyard")
		(35 "F.Fab" user)
		(33 "B.Fab" user)
	)
	(footprint "antmicro-footprints:R_0402_1005Metric"
		(layer "B.Cu")
		(at 177.2 148.9 180)
		(descr "Resistor SMD 0402")
		(tags "resistor SMD 0402")
		(property "Reference" "R4"
			(at -0.95 -1.45 0)
			(layer "B.SilkS")
			(effects
				(font
					(size 0.7 0.7)
					(thickness 0.15)
				)
				(justify left bottom mirror)
			)
		)
		(property "Value" "R_0R_0402"
			(at -1.011843 -1.772047 0)
			(layer "B.Fab")
			(hide yes)
			(effects
				(font
					(size 0.7 0.7)
					(thickness 0.15)
				)
				(justify left bottom mirror)
			)
		)
		(property "Datasheet" "https://industrial.panasonic.com/cdbs/www-data/pdf/RDA0000/AOA0000C301.pdf"
			(at 0 0 180)
			(layer "F.Fab")
			(hide yes)
			(effects
				(font
					(size 1.27 1.27)
					(thickness 0.15)
				)
			)
		)
		(property "Description" "SMD Chip Resistor, Jumper, 0 ohm, 100 mW, 0402 [1005 Metric], Thick Film, General Purpose"
			(at 0 0 180)
			(layer "F.Fab")
			(hide yes)
			(effects
				(font
					(size 1.27 1.27)
					(thickness 0.15)
				)
			)
		)
		(property "Author" "Antmicro"
			(at 354.4 297.8 0)
			(layer "B.Fab")
			(hide yes)
			(effects
				(font
					(size 1 1)
					(thickness 0.15)
				)
				(justify mirror)
			)
		)
		(property "Current" "1A"
			(at 354.4 297.8 0)
			(layer "B.Fab")
			(hide yes)
			(effects
				(font
					(size 1 1)
					(thickness 0.15)
				)
				(justify mirror)
			)
		)
		(property "License" "Apache-2.0"
			(at 354.4 297.8 0)
			(layer "B.Fab")
			(hide yes)
			(effects
				(font
					(size 1 1)
					(thickness 0.15)
				)
				(justify mirror)
			)
		)
		(property "MPN" "ERJ2GE0R00X"
			(at 354.4 297.8 0)
			(layer "B.Fab")
			(hide yes)
			(effects
				(font
					(size 1 1)
					(thickness 0.15)
				)
				(justify mirror)
			)
		)
		(property "Manufacturer" "Panasonic"
			(at 354.4 297.8 0)
			(layer "B.Fab")
			(hide yes)
			(effects
				(font
					(size 1 1)
					(thickness 0.15)
				)
				(justify mirror)
			)
		)
		(property "Public" ""
			(at 354.4 297.8 0)
			(layer "B.Fab")
			(hide yes)
			(effects
				(font
					(size 1 1)
					(thickness 0.15)
				)
				(justify mirror)
			)
		)
		(property "Tolerance" "~"
			(at 354.4 297.8 0)
			(layer "B.Fab")
			(hide yes)
			(effects
				(font
					(size 1 1)
					(thickness 0.15)
				)
				(justify mirror)
			)
		)
		(property "Val" "0R"
			(at 354.4 297.8 0)
			(layer "B.Fab")
			(hide yes)
			(effects
				(font
					(size 1 1)
					(thickness 0.15)
				)
				(justify mirror)
			)
		)
		(sheetname "/Supply/")
		(sheetfile "supply.kicad_sch")
		(attr smd)
		(fp_rect
			(start -0.925 0.47)
			(end 0.925 -0.47)
			(stroke
				(width 0.05)
				(type default)
			)
			(fill no)
			(layer "B.CrtYd")
		)
		(fp_rect
			(start -0.5 0.25)
			(end 0.5 -0.25)
			(stroke
				(width 0.15)
				(type solid)
			)
			(fill no)
			(layer "B.Fab")
		)
		(fp_text user "Author: Antmicro"
			(at -0.95 -4.169 0)
			(layer "B.Fab")
			(effects
				(font
					(size 0.7 0.7)
					(thickness 0.15)
				)
				(justify left bottom mirror)
			)
		)
		(fp_text user "License: Apache-2.0"
			(at -0.95 -5.169 0)
			(layer "B.Fab")
			(effects
				(font
					(size 0.7 0.7)
					(thickness 0.15)
				)
				(justify left bottom mirror)
			)
		)
		(fp_text user "${REFERENCE}"
			(at -0.95 -3.168 0)
			(layer "B.Fab")
			(effects
				(font
					(size 0.7 0.7)
					(thickness 0.15)
				)
				(justify left bottom mirror)
			)
		)
		(pad "1" smd roundrect
			(at -0.48 0 180)
			(size 0.59 0.64)
			(layers "B.Cu" "B.Mask" "B.Paste")
			(roundrect_rratio 0.25)
			(net 417 "GND")
			(pintype "passive")
		)
		(pad "2" smd roundrect
			(at 0.48 0 180)
			(size 0.59 0.64)
			(layers "B.Cu" "B.Mask" "B.Paste")
			(roundrect_rratio 0.25)
			(net 260 "Net-(U6-ADDRSEL)")
			(pintype "passive")
		)
	)
	(footprint "antmicro-footprints:R_0402_1005Metric"
		(layer "B.Cu")
		(at 184.75 118.95 90)
		(descr "Resistor SMD 0402")
		(tags "resistor SMD 0402")
		(property "Reference" "R5"
			(at 2.375 0.4 270)
			(layer "B.SilkS")
			(effects
				(font
					(size 0.7 0.7)
					(thickness 0.15)
				)
				(justify left bottom mirror)
			)
		)
		(property "Value" "R_49k9_0402"
			(at -1.011843 -1.772047 270)
			(layer "B.Fab")
			(hide yes)
			(effects
				(font
					(size 0.7 0.7)
					(thickness 0.15)
				)
				(justify left bottom mirror)
			)
		)
		(property "Datasheet" "https://www.bourns.com/docs/product-datasheets/cr.pdf"
			(at 0 0 90)
			(layer "F.Fab")
			(hide yes)
			(effects
				(font
					(size 1.27 1.27)
					(thickness 0.15)
				)
			)
		)
		(property "Description" "SMD Chip Resistor, 49.9 kohm, ± 1%, 63 mW, 0402 [1005 Metric], Thick Film, General Purpose"
			(at 0 0 90)
			(layer "F.Fab")
			(hide yes)
			(effects
				(font
					(size 1.27 1.27)
					(thickness 0.15)
				)
			)
		)
		(property "Author" "Antmicro"
			(at 303.7 -65.8 0)
			(layer "B.Fab")
			(hide yes)
			(effects
				(font
					(size 1 1)
					(thickness 0.15)
				)
				(justify mirror)
			)
		)
		(property "License" "Apache-2.0"
			(at 303.7 -65.8 0)
			(layer "B.Fab")
			(hide yes)
			(effects
				(font
					(size 1 1)
					(thickness 0.15)
				)
				(justify mirror)
			)
		)
		(property "MPN" "CR0402-FX-4992GLF"
			(at 303.7 -65.8 0)
			(layer "B.Fab")
			(hide yes)
			(effects
				(font
					(size 1 1)
					(thickness 0.15)
				)
				(justify mirror)
			)
		)
		(property "Manufacturer" "Bourns"
			(at 303.7 -65.8 0)
			(layer "B.Fab")
			(hide yes)
			(effects
				(font
					(size 1 1)
					(thickness 0.15)
				)
				(justify mirror)
			)
		)
		(property "Public" ""
			(at 303.7 -65.8 0)
			(layer "B.Fab")
			(hide yes)
			(effects
				(font
					(size 1 1)
					(thickness 0.15)
				)
				(justify mirror)
			)
		)
		(property "Tolerance" "1%"
			(at 303.7 -65.8 0)
			(layer "B.Fab")
			(hide yes)
			(effects
				(font
					(size 1 1)
					(thickness 0.15)
				)
				(justify mirror)
			)
		)
		(property "Val" "49k9"
			(at 303.7 -65.8 0)
			(layer "B.Fab")
			(hide yes)
			(effects
				(font
					(size 1 1)
					(thickness 0.15)
				)
				(justify mirror)
			)
		)
		(sheetname "/Supply/")
		(sheetfile "supply.kicad_sch")
		(attr smd)
		(fp_rect
			(start -0.925 0.47)
			(end 0.925 -0.47)
			(stroke
				(width 0.05)
				(type default)
			)
			(fill no)
			(layer "B.CrtYd")
		)
		(fp_rect
			(start -0.5 0.25)
			(end 0.5 -0.25)
			(stroke
				(width 0.15)
				(type solid)
			)
			(fill no)
			(layer "B.Fab")
		)
		(fp_text user "License: Apache-2.0"
			(at -0.95 -5.169 270)
			(layer "B.Fab")
			(effects
				(font
					(size 0.7 0.7)
					(thickness 0.15)
				)
				(justify left bottom mirror)
			)
		)
		(fp_text user "Author: Antmicro"
			(at -0.95 -4.169 270)
			(layer "B.Fab")
			(effects
				(font
					(size 0.7 0.7)
					(thickness 0.15)
				)
				(justify left bottom mirror)
			)
		)
		(fp_text user "${REFERENCE}"
			(at -0.95 -3.168 270)
			(layer "B.Fab")
			(effects
				(font
					(size 0.7 0.7)
					(thickness 0.15)
				)
				(justify left bottom mirror)
			)
		)
		(pad "1" smd roundrect
			(at -0.48 0 90)
			(size 0.59 0.64)
			(layers "B.Cu" "B.Mask" "B.Paste")
			(roundrect_rratio 0.25)
			(net 212 "GLOBAL_EN")
			(pintype "passive")
		)
		(pad "2" smd roundrect
			(at 0.48 0 90)
			(size 0.59 0.64)
			(layers "B.Cu" "B.Mask" "B.Paste")
			(roundrect_rratio 0.25)
			(net 90 "+5V")
			(pintype "passive")
		)
	)
	(footprint "antmicro-footprints:C_0402_1005Metric"
		(layer "B.Cu")
		(at 175.27 128.8295 -90)
		(descr "Capacitor SMD 0402")
		(tags "capacitor SMD 0402")
		(property "Reference" "C146"
			(at -3.0095 -1.35 270)
			(layer "B.SilkS")
			(effects
				(font
					(size 0.7 0.7)
					(thickness 0.15)
				)
				(justify left bottom mirror)
			)
		)
		(property "Value" "C_1u_0402"
			(at -1.022927 -2.155213 90)
			(layer "B.Fab")
			(hide yes)
			(effects
				(font
					(size 0.7 0.7)
					(thickness 0.15)
				)
				(justify left bottom mirror)
			)
		)
		(property "Datasheet" "https://product.tdk.com/en/search/capacitor/ceramic/mlcc/info?part_no=C1005X6S1A105K050BC"
			(at 0 0 270)
			(layer "F.Fab")
			(hide yes)
			(effects
				(font
					(size 1.27 1.27)
					(thickness 0.15)
				)
			)
		)
		(property "Description" "SMD Multilayer Ceramic Capacitor, 1 µF, 10 V, 0402 [1005 Metric], ± 10%, X6S, C"
			(at 0 0 270)
			(layer "F.Fab")
			(hide yes)
			(effects
				(font
					(size 1.27 1.27)
					(thickness 0.15)
				)
			)
		)
		(property "Author" "Antmicro"
			(at 46.4405 304.0995 0)
			(layer "B.Fab")
			(hide yes)
			(effects
				(font
					(size 1 1)
					(thickness 0.15)
				)
				(justify mirror)
			)
		)
		(property "Dielectric" "X5R"
			(at 46.4405 304.0995 0)
			(layer "B.Fab")
			(hide yes)
			(effects
				(font
					(size 1 1)
					(thickness 0.15)
				)
				(justify mirror)
			)
		)
		(property "License" "Apache-2.0"
			(at 46.4405 304.0995 0)
			(layer "B.Fab")
			(hide yes)
			(effects
				(font
					(size 1 1)
					(thickness 0.15)
				)
				(justify mirror)
			)
		)
		(property "MPN" "C1005X6S1A105K050BC"
			(at 46.4405 304.0995 0)
			(layer "B.Fab")
			(hide yes)
			(effects
				(font
					(size 1 1)
					(thickness 0.15)
				)
				(justify mirror)
			)
		)
		(property "Manufacturer" "TDK"
			(at 46.4405 304.0995 0)
			(layer "B.Fab")
			(hide yes)
			(effects
				(font
					(size 1 1)
					(thickness 0.15)
				)
				(justify mirror)
			)
		)
		(property "Public" ""
			(at 46.4405 304.0995 0)
			(layer "B.Fab")
			(hide yes)
			(effects
				(font
					(size 1 1)
					(thickness 0.15)
				)
				(justify mirror)
			)
		)
		(property "Val" "1u"
			(at 46.4405 304.0995 0)
			(layer "B.Fab")
			(hide yes)
			(effects
				(font
					(size 1 1)
					(thickness 0.15)
				)
				(justify mirror)
			)
		)
		(property "Voltage" "16V"
			(at 46.4405 304.0995 0)
			(layer "B.Fab")
			(hide yes)
			(effects
				(font
					(size 1 1)
					(thickness 0.15)
				)
				(justify mirror)
			)
		)
		(sheetname "/LPDDR4/")
		(sheetfile "lpddr.kicad_sch")
		(attr smd)
		(fp_rect
			(start -0.925 0.47)
			(end 0.925 -0.47)
			(stroke
				(width 0.05)
				(type default)
			)
			(fill no)
			(layer "B.CrtYd")
		)
		(fp_line
			(start -0.494 0.25)
			(end 0.504 0.25)
			(stroke
				(width 0.15)
				(type solid)
			)
			(layer "B.Fab")
		)
		(fp_line
			(start 0.504 0.25)
			(end 0.504 -0.248)
			(stroke
				(width 0.15)
				(type solid)
			)
			(layer "B.Fab")
		)
		(fp_line
			(start -0.494 -0.248)
			(end -0.494 0.25)
			(stroke
				(width 0.15)
				(type solid)
			)
			(layer "B.Fab")
		)
		(fp_line
			(start 0.504 -0.248)
			(end -0.494 -0.248)
			(stroke
				(width 0.15)
				(type solid)
			)
			(layer "B.Fab")
		)
		(fp_text user "${REFERENCE}"
			(at -0.939 -4.599 90)
			(layer "B.Fab")
			(effects
				(font
					(size 0.7 0.7)
					(thickness 0.15)
				)
				(justify left bottom mirror)
			)
		)
		(fp_text user "Author: Antmicro"
			(at -0.939 -3.399 90)
			(layer "B.Fab")
			(effects
				(font
					(size 0.7 0.7)
					(thickness 0.15)
				)
				(justify left bottom mirror)
			)
		)
		(fp_text user "License: Apache-2.0"
			(at -0.939 -5.799 90)
			(layer "B.Fab")
			(effects
				(font
					(size 0.7 0.7)
					(thickness 0.15)
				)
				(justify left bottom mirror)
			)
		)
		(pad "1" smd roundrect
			(at -0.48 0 270)
			(size 0.59 0.64)
			(layers "B.Cu" "B.Mask" "B.Paste")
			(roundrect_rratio 0.25)
			(net 417 "GND")
			(pintype "passive")
		)
		(pad "2" smd roundrect
			(at 0.48 0 270)
			(size 0.59 0.64)
			(layers "B.Cu" "B.Mask" "B.Paste")
			(roundrect_rratio 0.25)
			(net 2 "+1V1")
			(pintype "passive")
		)
	)
	(footprint "antmicro-footprints:R_0402_1005Metric"
		(layer "B.Cu")
		(at 213.061 124.754 180)
		(descr "Resistor SMD 0402")
		(tags "resistor SMD 0402")
		(property "Reference" "R95"
			(at 0.936 -1.046 0)
			(layer "B.SilkS")
			(effects
				(font
					(size 0.7 0.7)
					(thickness 0.15)
				)
				(justify left bottom mirror)
			)
		)
		(property "Value" "R_4k7_0402"
			(at -1.011843 -1.772047 0)
			(layer "B.Fab")
			(hide yes)
			(effects
				(font
					(size 0.7 0.7)
					(thickness 0.15)
				)
				(justify left bottom mirror)
			)
		)
		(property "Datasheet" "https://www.bourns.com/docs/product-datasheets/cr.pdf"
			(at 0 0 180)
			(layer "F.Fab")
			(hide yes)
			(effects
				(font
					(size 1.27 1.27)
					(thickness 0.15)
				)
			)
		)
		(property "Description" "SMD Chip Resistor, 4.7 kohm, ± 1%, 62.5 mW, 0402 [1005 Metric], Thick Film, General Purpose"
			(at 0 0 180)
			(layer "F.Fab")
			(hide yes)
			(effects
				(font
					(size 1.27 1.27)
					(thickness 0.15)
				)
			)
		)
		(property "Author" "Antmicro"
			(at 426.122 249.508 0)
			(layer "B.Fab")
			(hide yes)
			(effects
				(font
					(size 1 1)
					(thickness 0.15)
				)
				(justify mirror)
			)
		)
		(property "License" "Apache-2.0"
			(at 426.122 249.508 0)
			(layer "B.Fab")
			(hide yes)
			(effects
				(font
					(size 1 1)
					(thickness 0.15)
				)
				(justify mirror)
			)
		)
		(property "MPN" "CR0402-FX-4701GLF"
			(at 426.122 249.508 0)
			(layer "B.Fab")
			(hide yes)
			(effects
				(font
					(size 1 1)
					(thickness 0.15)
				)
				(justify mirror)
			)
		)
		(property "Manufacturer" "Bourns"
			(at 426.122 249.508 0)
			(layer "B.Fab")
			(hide yes)
			(effects
				(font
					(size 1 1)
					(thickness 0.15)
				)
				(justify mirror)
			)
		)
		(property "Public" ""
			(at 426.122 249.508 0)
			(layer "B.Fab")
			(hide yes)
			(effects
				(font
					(size 1 1)
					(thickness 0.15)
				)
				(justify mirror)
			)
		)
		(property "Tolerance" "1%"
			(at 426.122 249.508 0)
			(layer "B.Fab")
			(hide yes)
			(effects
				(font
					(size 1 1)
					(thickness 0.15)
				)
				(justify mirror)
			)
		)
		(property "Val" "4k7"
			(at 426.122 249.508 0)
			(layer "B.Fab")
			(hide yes)
			(effects
				(font
					(size 1 1)
					(thickness 0.15)
				)
				(justify mirror)
			)
		)
		(sheetname "/Ethernet/")
		(sheetfile "ethernet.kicad_sch")
		(attr smd)
		(fp_rect
			(start -0.925 0.47)
			(end 0.925 -0.47)
			(stroke
				(width 0.05)
				(type default)
			)
			(fill no)
			(layer "B.CrtYd")
		)
		(fp_rect
			(start -0.5 0.25)
			(end 0.5 -0.25)
			(stroke
				(width 0.15)
				(type solid)
			)
			(fill no)
			(layer "B.Fab")
		)
		(fp_text user "Author: Antmicro"
			(at -0.95 -4.169 0)
			(layer "B.Fab")
			(effects
				(font
					(size 0.7 0.7)
					(thickness 0.15)
				)
				(justify left bottom mirror)
			)
		)
		(fp_text user "${REFERENCE}"
			(at -0.95 -3.168 0)
			(layer "B.Fab")
			(effects
				(font
					(size 0.7 0.7)
					(thickness 0.15)
				)
				(justify left bottom mirror)
			)
		)
		(fp_text user "License: Apache-2.0"
			(at -0.95 -5.169 0)
			(layer "B.Fab")
			(effects
				(font
					(size 0.7 0.7)
					(thickness 0.15)
				)
				(justify left bottom mirror)
			)
		)
		(pad "1" smd roundrect
			(at -0.48 0 180)
			(size 0.59 0.64)
			(layers "B.Cu" "B.Mask" "B.Paste")
			(roundrect_rratio 0.25)
			(net 282 "/Ethernet/ETH_RXCTRL")
			(pintype "passive")
		)
		(pad "2" smd roundrect
			(at 0.48 0 180)
			(size 0.59 0.64)
			(layers "B.Cu" "B.Mask" "B.Paste")
			(roundrect_rratio 0.25)
			(net 50 "+3V3")
			(pintype "passive")
		)
	)
	(footprint "antmicro-footprints:R_0402_1005Metric"
		(layer "B.Cu")
		(at 219.32 155.12 180)
		(descr "Resistor SMD 0402")
		(tags "resistor SMD 0402")
		(property "Reference" "R88"
			(at 0.96 -0.43 0)
			(layer "B.SilkS")
			(effects
				(font
					(size 0.7 0.7)
					(thickness 0.15)
				)
				(justify left bottom mirror)
			)
		)
		(property "Value" "R_50R_0402"
			(at -1.011843 -1.772047 0)
			(layer "B.Fab")
			(hide yes)
			(effects
				(font
					(size 0.7 0.7)
					(thickness 0.15)
				)
				(justify left bottom mirror)
			)
		)
		(property "Datasheet" "https://www.bourns.com/docs/product-datasheets/cr.pdf"
			(at 0 0 180)
			(layer "F.Fab")
			(hide yes)
			(effects
				(font
					(size 1.27 1.27)
					(thickness 0.15)
				)
			)
		)
		(property "Description" "SMD Chip Resistor"
			(at 0 0 180)
			(layer "F.Fab")
			(hide yes)
			(effects
				(font
					(size 1.27 1.27)
					(thickness 0.15)
				)
			)
		)
		(property "Author" "Antmicro"
			(at 438.64 310.24 0)
			(layer "B.Fab")
			(hide yes)
			(effects
				(font
					(size 1 1)
					(thickness 0.15)
				)
				(justify mirror)
			)
		)
		(property "License" "Apache-2.0"
			(at 438.64 310.24 0)
			(layer "B.Fab")
			(hide yes)
			(effects
				(font
					(size 1 1)
					(thickness 0.15)
				)
				(justify mirror)
			)
		)
		(property "MPN" "CR0402-FX-50R0GLF"
			(at 438.64 310.24 0)
			(layer "B.Fab")
			(hide yes)
			(effects
				(font
					(size 1 1)
					(thickness 0.15)
				)
				(justify mirror)
			)
		)
		(property "Manufacturer" "Bourns"
			(at 438.64 310.24 0)
			(layer "B.Fab")
			(hide yes)
			(effects
				(font
					(size 1 1)
					(thickness 0.15)
				)
				(justify mirror)
			)
		)
		(property "Public" ""
			(at 438.64 310.24 0)
			(layer "B.Fab")
			(hide yes)
			(effects
				(font
					(size 1 1)
					(thickness 0.15)
				)
				(justify mirror)
			)
		)
		(property "Tolerance" "1%"
			(at 438.64 310.24 0)
			(layer "B.Fab")
			(hide yes)
			(effects
				(font
					(size 1 1)
					(thickness 0.15)
				)
				(justify mirror)
			)
		)
		(property "Val" "50R"
			(at 438.64 310.24 0)
			(layer "B.Fab")
			(hide yes)
			(effects
				(font
					(size 1 1)
					(thickness 0.15)
				)
				(justify mirror)
			)
		)
		(sheetname "/PCIe/")
		(sheetfile "pcie.kicad_sch")
		(attr smd)
		(fp_rect
			(start -0.925 0.47)
			(end 0.925 -0.47)
			(stroke
				(width 0.05)
				(type default)
			)
			(fill no)
			(layer "B.CrtYd")
		)
		(fp_rect
			(start -0.5 0.25)
			(end 0.5 -0.25)
			(stroke
				(width 0.15)
				(type solid)
			)
			(fill no)
			(layer "B.Fab")
		)
		(fp_text user "Author: Antmicro"
			(at -0.95 -4.169 0)
			(layer "B.Fab")
			(effects
				(font
					(size 0.7 0.7)
					(thickness 0.15)
				)
				(justify left bottom mirror)
			)
		)
		(fp_text user "License: Apache-2.0"
			(at -0.95 -5.169 0)
			(layer "B.Fab")
			(effects
				(font
					(size 0.7 0.7)
					(thickness 0.15)
				)
				(justify left bottom mirror)
			)
		)
		(fp_text user "${REFERENCE}"
			(at -0.95 -3.168 0)
			(layer "B.Fab")
			(effects
				(font
					(size 0.7 0.7)
					(thickness 0.15)
				)
				(justify left bottom mirror)
			)
		)
		(pad "1" smd roundrect
			(at -0.48 0 180)
			(size 0.59 0.64)
			(layers "B.Cu" "B.Mask" "B.Paste")
			(roundrect_rratio 0.25)
			(net 417 "GND")
			(pintype "passive")
		)
		(pad "2" smd roundrect
			(at 0.48 0 180)
			(size 0.59 0.64)
			(layers "B.Cu" "B.Mask" "B.Paste")
			(roundrect_rratio 0.25)
			(net 314 "Net-(U17-CLK1-)")
			(pintype "passive")
		)
	)
)
